# T6G (Grand Teton) — schematic netlist excerpt (pin names and nets, part order shuffled) for the footprints in the layout excerpt that follows; sources: Cadence DE-HDL packaged netlist, KiCad conversion of 04192023_DAF0TMB3IC0_F0TG_MB_C_brd_V02_OCP.brd

R6745  Q_RES  1K 1% CHIP  pkg 0402LF  page 358 : A = RT_BOARD_ID_ID0 ; B = GND
R3144  Q_RES  0 5% CHIP  pkg 0402LF  page 134 : A = P12V_OCP_PWRGD_1 ; B = HP_LVC3_OCP_V3_1_P12V_PWRGD
PC88  Q_CAP  22UF 4V 20% EMPTY  pkg C0805  page 226 : A = PVDD18_S5_P1 ; B = GND

(kicad_pcb
	(version 20260206)
	(generator "pcbnew")
	(generator_version "10.0")
	(general
		(thickness 1.6)
		(legacy_teardrops no)
	)
	(paper "A4")
	(title_block
		(title "04192023_DAF0TMB3IC0_F0TG_MB_C_brd_V02_OCP.brd")
		(comment 1 "Grand Teton / footprints 2497-2499 of 8354")
	)
	(layers
		(0 "F.Cu" signal "TOP")
		(4 "In1.Cu" signal "GND")
		(6 "In2.Cu" signal "IN1")
		(8 "In3.Cu" signal "GND1")
		(10 "In4.Cu" signal "IN2")
		(12 "In5.Cu" signal "GND2")
		(14 "In6.Cu" signal "IN3")
		(16 "In7.Cu" signal "GND3")
		(18 "In8.Cu" signal "VCC")
		(20 "In9.Cu" signal "VCC1")
		(22 "In10.Cu" signal "GND4")
		(24 "In11.Cu" signal "IN4")
		(26 "In12.Cu" signal "GND5")
		(28 "In13.Cu" signal "IN5")
		(30 "In14.Cu" signal "GND6")
		(32 "In15.Cu" signal "IN6")
		(34 "In16.Cu" signal "GND7")
		(2 "B.Cu" signal "BOTTOM")
		(9 "F.Adhes" user "F.Adhesive")
		(11 "B.Adhes" user "B.Adhesive")
		(13 "F.Paste" user "Package Geometry/Pastemask Top")
		(15 "B.Paste" user "Package Geometry/Pastemask Bottom")
		(5 "F.SilkS" user "Ref Des/Silkscreen Top")
		(7 "B.SilkS" user "Ref Des/Silkscreen Bottom")
		(1 "F.Mask" user "Board Geometry/Soldermask Top")
		(3 "B.Mask" user "Board Geometry/Soldermask Bottom")
		(17 "Dwgs.User" user "User.Drawings")
		(19 "Cmts.User" user "User.Comments")
		(21 "Eco1.User" user "User.Eco1")
		(23 "Eco2.User" user "User.Eco2")
		(25 "Edge.Cuts" user "Board Geometry/Outline")
		(27 "Margin" user)
		(31 "F.CrtYd" user "Package Geometry/Place Bound Top")
		(29 "B.CrtYd" user "Package Geometry/Place Bound Bottom")
		(35 "F.Fab" user "Ref Des/Assembly Top")
		(33 "B.Fab" user "Ref Des/Assembly Bottom")
	)
	(footprint ""
		(layer "F.Cu")
		(at 454.447402 -18.030698)
		(property "Reference" "R3144"
			(at 0 0 0)
			(layer "F.SilkS")
			(hide yes)
			(effects
				(font
					(size 1.27 1.27)
				)
			)
		)
		(property "Value" ""
			(at 0 0 0)
			(layer "F.Fab")
			(effects
				(font
					(size 1.27 1.27)
				)
			)
		)
		(duplicate_pad_numbers_are_jumpers no)
		(fp_line
			(start -0.7874 -0.4064)
			(end 0.7874 -0.4064)
			(stroke
				(width 0.1524)
				(type default)
			)
			(layer "F.SilkS")
		)
		(fp_line
			(start -0.7874 0.4064)
			(end -0.7874 -0.4064)
			(stroke
				(width 0.1524)
				(type default)
			)
			(layer "F.SilkS")
		)
		(fp_line
			(start 0.7874 -0.4064)
			(end 0.7874 0.4064)
			(stroke
				(width 0.1524)
				(type default)
			)
			(layer "F.SilkS")
		)
		(fp_line
			(start 0.7874 0.4064)
			(end -0.7874 0.4064)
			(stroke
				(width 0.1524)
				(type default)
			)
			(layer "F.SilkS")
		)
		(fp_line
			(start -0.67945 -0.305054)
			(end -0.12065 -0.305054)
			(stroke
				(width 0.1)
				(type default)
			)
			(layer "F.Fab")
		)
		(fp_line
			(start -0.67945 0.3048)
			(end -0.67945 -0.305054)
			(stroke
				(width 0.1)
				(type default)
			)
			(layer "F.Fab")
		)
		(fp_line
			(start -0.12065 -0.305054)
			(end -0.12065 -0.2794)
			(stroke
				(width 0.1)
				(type default)
			)
			(layer "F.Fab")
		)
		(fp_line
			(start -0.12065 -0.2794)
			(end 0.12065 -0.2794)
			(stroke
				(width 0.1)
				(type default)
			)
			(layer "F.Fab")
		)
		(fp_line
			(start -0.12065 0.2794)
			(end -0.12065 0.3048)
			(stroke
				(width 0.1)
				(type default)
			)
			(layer "F.Fab")
		)
		(fp_line
			(start -0.12065 0.3048)
			(end -0.67945 0.3048)
			(stroke
				(width 0.1)
				(type default)
			)
			(layer "F.Fab")
		)
		(fp_line
			(start 0.120396 0.2794)
			(end -0.12065 0.2794)
			(stroke
				(width 0.1)
				(type default)
			)
			(layer "F.Fab")
		)
		(fp_line
			(start 0.120396 0.3048)
			(end 0.120396 0.2794)
			(stroke
				(width 0.1)
				(type default)
			)
			(layer "F.Fab")
		)
		(fp_line
			(start 0.12065 -0.3048)
			(end 0.67945 -0.3048)
			(stroke
				(width 0.1)
				(type default)
			)
			(layer "F.Fab")
		)
		(fp_line
			(start 0.12065 -0.2794)
			(end 0.12065 -0.3048)
			(stroke
				(width 0.1)
				(type default)
			)
			(layer "F.Fab")
		)
		(fp_line
			(start 0.67945 -0.3048)
			(end 0.67945 0.3048)
			(stroke
				(width 0.1)
				(type default)
			)
			(layer "F.Fab")
		)
		(fp_line
			(start 0.67945 0.3048)
			(end 0.120396 0.3048)
			(stroke
				(width 0.1)
				(type default)
			)
			(layer "F.Fab")
		)
		(pad "1" smd circle
			(at -0.40005 0)
			(size 0 0)
			(layers "F.Cu" "F.Mask" "F.Paste")
			(net "P12V_OCP_PWRGD_1")
		)
		(pad "2" smd circle
			(at 0.40005 0)
			(size 0 0)
			(layers "F.Cu" "F.Mask" "F.Paste")
			(net "HP_LVC3_OCP_V3_1_P12V_PWRGD")
		)
	)
	(footprint ""
		(layer "F.Cu")
		(at 52.143406 -150.15083 180)
		(property "Reference" "PC88"
			(at 0 0 180)
			(layer "F.SilkS")
			(hide yes)
			(effects
				(font
					(size 1.27 1.27)
				)
			)
		)
		(property "Value" ""
			(at 0 0 180)
			(layer "F.Fab")
			(effects
				(font
					(size 1.27 1.27)
				)
			)
		)
		(duplicate_pad_numbers_are_jumpers no)
		(fp_line
			(start 1.524 0.762)
			(end -1.524 0.762)
			(stroke
				(width 0.1524)
				(type default)
			)
			(layer "F.SilkS")
		)
		(fp_line
			(start 1.524 -0.762)
			(end 1.524 0.762)
			(stroke
				(width 0.1524)
				(type default)
			)
			(layer "F.SilkS")
		)
		(fp_line
			(start -1.524 0.762)
			(end -1.524 -0.762)
			(stroke
				(width 0.1524)
				(type default)
			)
			(layer "F.SilkS")
		)
		(fp_line
			(start -1.524 -0.762)
			(end 1.524 -0.762)
			(stroke
				(width 0.1524)
				(type default)
			)
			(layer "F.SilkS")
		)
		(fp_line
			(start 1.1049 0.724916)
			(end 1.1049 -0.724916)
			(stroke
				(width 0.1)
				(type default)
			)
			(layer "F.Fab")
		)
		(fp_line
			(start 1.1049 -0.724916)
			(end -1.1049 -0.724916)
			(stroke
				(width 0.1)
				(type default)
			)
			(layer "F.Fab")
		)
		(fp_line
			(start -1.1049 0.724916)
			(end 1.1049 0.724916)
			(stroke
				(width 0.1)
				(type default)
			)
			(layer "F.Fab")
		)
		(fp_line
			(start -1.1049 -0.724916)
			(end -1.1049 0.724916)
			(stroke
				(width 0.1)
				(type default)
			)
			(layer "F.Fab")
		)
		(pad "1" smd rect
			(at -0.889 0)
			(size 1.016 1.27)
			(layers "F.Cu" "F.Mask" "F.Paste")
			(net "PVDD18_S5_P1")
		)
		(pad "2" smd rect
			(at 0.889 0)
			(size 1.016 1.27)
			(layers "F.Cu" "F.Mask" "F.Paste")
			(net "GND")
		)
	)
	(footprint ""
		(layer "F.Cu")
		(at 176.115218 -92.685616 -90)
		(property "Reference" "R6745"
			(at 0 0 270)
			(layer "F.SilkS")
			(hide yes)
			(effects
				(font
					(size 1.27 1.27)
				)
			)
		)
		(property "Value" ""
			(at 0 0 270)
			(layer "F.Fab")
			(effects
				(font
					(size 1.27 1.27)
				)
			)
		)
		(duplicate_pad_numbers_are_jumpers no)
		(fp_line
			(start -0.7874 0.4064)
			(end -0.7874 -0.4064)
			(stroke
				(width 0.1524)
				(type default)
			)
			(layer "F.SilkS")
		)
		(fp_line
			(start 0.7874 0.4064)
			(end -0.7874 0.4064)
			(stroke
				(width 0.1524)
				(type default)
			)
			(layer "F.SilkS")
		)
		(fp_line
			(start -0.7874 -0.4064)
			(end 0.7874 -0.4064)
			(stroke
				(width 0.1524)
				(type default)
			)
			(layer "F.SilkS")
		)
		(fp_line
			(start 0.7874 -0.4064)
			(end 0.7874 0.4064)
			(stroke
				(width 0.1524)
				(type default)
			)
			(layer "F.SilkS")
		)
		(fp_line
			(start -0.67945 0.3048)
			(end -0.67945 -0.305054)
			(stroke
				(width 0.1)
				(type default)
			)
			(layer "F.Fab")
		)
		(fp_line
			(start -0.12065 0.3048)
			(end -0.67945 0.3048)
			(stroke
				(width 0.1)
				(type default)
			)
			(layer "F.Fab")
		)
		(fp_line
			(start 0.120396 0.3048)
			(end 0.120396 0.2794)
			(stroke
				(width 0.1)
				(type default)
			)
			(layer "F.Fab")
		)
		(fp_line
			(start 0.67945 0.3048)
			(end 0.120396 0.3048)
			(stroke
				(width 0.1)
				(type default)
			)
			(layer "F.Fab")
		)
		(fp_line
			(start -0.12065 0.2794)
			(end -0.12065 0.3048)
			(stroke
				(width 0.1)
				(type default)
			)
			(layer "F.Fab")
		)
		(fp_line
			(start 0.120396 0.2794)
			(end -0.12065 0.2794)
			(stroke
				(width 0.1)
				(type default)
			)
			(layer "F.Fab")
		)
		(fp_line
			(start -0.12065 -0.2794)
			(end 0.12065 -0.2794)
			(stroke
				(width 0.1)
				(type default)
			)
			(layer "F.Fab")
		)
		(fp_line
			(start 0.12065 -0.2794)
			(end 0.12065 -0.3048)
			(stroke
				(width 0.1)
				(type default)
			)
			(layer "F.Fab")
		)
		(fp_line
			(start 0.12065 -0.3048)
			(end 0.67945 -0.3048)
			(stroke
				(width 0.1)
				(type default)
			)
			(layer "F.Fab")
		)
		(fp_line
			(start 0.67945 -0.3048)
			(end 0.67945 0.3048)
			(stroke
				(width 0.1)
				(type default)
			)
			(layer "F.Fab")
		)
		(fp_line
			(start -0.67945 -0.305054)
			(end -0.12065 -0.305054)
			(stroke
				(width 0.1)
				(type default)
			)
			(layer "F.Fab")
		)
		(fp_line
			(start -0.12065 -0.305054)
			(end -0.12065 -0.2794)
			(stroke
				(width 0.1)
				(type default)
			)
			(layer "F.Fab")
		)
		(pad "1" smd circle
			(at -0.40005 0 270)
			(size 0 0)
			(layers "F.Cu" "F.Mask" "F.Paste")
			(net "RT_BOARD_ID_ID0")
		)
		(pad "2" smd circle
			(at 0.40005 0 270)
			(size 0 0)
			(layers "F.Cu" "F.Mask" "F.Paste")
			(net "GND")
		)
	)
)
